(kicad_pcb
	(version 20260206)
	(generator "pcbnew")
	(generator_version "10.0")
	(general
		(thickness 1.6)
		(legacy_teardrops no)
	)
	(paper "A4")
	(title_block
		(title "03242023_DA0F0TMBIJ0_F0T_Motherboard_J_brd_V01_OCP.brd")
		(comment 1 "Grand Teton / footprints 1485-1490 of 6105")
	)
	(layers
		(0 "F.Cu" signal "TOP")
		(4 "In1.Cu" signal "GND")
		(6 "In2.Cu" signal "IN1")
		(8 "In3.Cu" signal "GND1")
		(10 "In4.Cu" signal "IN2")
		(12 "In5.Cu" signal "GND2")
		(14 "In6.Cu" signal "IN3")
		(16 "In7.Cu" signal "GND3")
		(18 "In8.Cu" signal "VCC")
		(20 "In9.Cu" signal "VCC1")
		(22 "In10.Cu" signal "GND4")
		(24 "In11.Cu" signal "IN4")
		(26 "In12.Cu" signal "GND5")
		(28 "In13.Cu" signal "IN5")
		(30 "In14.Cu" signal "GND6")
		(32 "In15.Cu" signal "IN6")
		(34 "In16.Cu" signal "GND7")
		(2 "B.Cu" signal "BOTTOM")
		(9 "F.Adhes" user "F.Adhesive")
		(11 "B.Adhes" user "B.Adhesive")
		(13 "F.Paste" user "Package Geometry/Pastemask Top")
		(15 "B.Paste" user "Package Geometry/Pastemask Bottom")
		(5 "F.SilkS" user "Ref Des/Silkscreen Top")
		(7 "B.SilkS" user "Ref Des/Silkscreen Bottom")
		(1 "F.Mask" user "Board Geometry/Soldermask Top")
		(3 "B.Mask" user "Board Geometry/Soldermask Bottom")
		(17 "Dwgs.User" user "User.Drawings")
		(19 "Cmts.User" user "User.Comments")
		(21 "Eco1.User" user "User.Eco1")
		(23 "Eco2.User" user "User.Eco2")
		(25 "Edge.Cuts" user "Board Geometry/Outline")
		(27 "Margin" user)
		(31 "F.CrtYd" user "Package Geometry/Place Bound Top")
		(29 "B.CrtYd" user "Package Geometry/Place Bound Bottom")
		(35 "F.Fab" user "Ref Des/Assembly Top")
		(33 "B.Fab" user "Ref Des/Assembly Bottom")
	)
	(footprint ""
		(layer "F.Cu")
		(at 111.764826 -402.145246 90)
		(property "Reference" "U257"
			(at 1.622552 -4.533646 0)
			(unlocked yes)
			(layer "F.SilkS")
			(effects
				(font
					(size 0.7874 0.5842)
					(thickness 0.1524)
				)
				(justify left)
			)
		)
		(property "Value" ""
			(at 0 0 90)
			(layer "F.Fab")
			(effects
				(font
					(size 1.27 1.27)
				)
			)
		)
		(duplicate_pad_numbers_are_jumpers no)
		(fp_line
			(start 1.38176 -1.100074)
			(end 0.592074 -1.100074)
			(stroke
				(width 0.1524)
				(type default)
			)
			(layer "F.SilkS")
		)
		(fp_line
			(start 0.592074 -1.100074)
			(end 0 -0.508)
			(stroke
				(width 0.1524)
				(type default)
			)
			(layer "F.SilkS")
		)
		(fp_line
			(start -0.592074 -1.100074)
			(end -1.38176 -1.100074)
			(stroke
				(width 0.1524)
				(type default)
			)
			(layer "F.SilkS")
		)
		(fp_line
			(start -1.38176 -1.100074)
			(end -1.38176 1.100074)
			(stroke
				(width 0.1524)
				(type default)
			)
			(layer "F.SilkS")
		)
		(fp_line
			(start 0 -0.508)
			(end -0.592074 -1.100074)
			(stroke
				(width 0.1524)
				(type default)
			)
			(layer "F.SilkS")
		)
		(fp_line
			(start 1.38176 1.100074)
			(end 1.38176 -1.100074)
			(stroke
				(width 0.1524)
				(type default)
			)
			(layer "F.SilkS")
		)
		(fp_line
			(start -1.38176 1.100074)
			(end 1.38176 1.100074)
			(stroke
				(width 0.1524)
				(type default)
			)
			(layer "F.SilkS")
		)
		(fp_poly
			(pts
				(xy -1.50241 -0.649986) (xy -1.9431 -0.429768) (xy -1.9431 -0.870204)
			)
			(stroke
				(width 0)
				(type default)
			)
			(fill yes)
			(layer "F.SilkS")
		)
		(fp_line
			(start 0.674878 -1.100074)
			(end -0.674878 -1.100074)
			(stroke
				(width 0.1)
				(type default)
			)
			(layer "F.Fab")
		)
		(fp_line
			(start -0.674878 -1.100074)
			(end -0.674878 1.100074)
			(stroke
				(width 0.1)
				(type default)
			)
			(layer "F.Fab")
		)
		(fp_line
			(start 0.674878 1.100074)
			(end 0.674878 -1.100074)
			(stroke
				(width 0.1)
				(type default)
			)
			(layer "F.Fab")
		)
		(fp_line
			(start -0.674878 1.100074)
			(end 0.674878 1.100074)
			(stroke
				(width 0.1)
				(type default)
			)
			(layer "F.Fab")
		)
		(fp_poly
			(pts
				(xy -1.9431 -0.870204) (xy -1.50241 -0.649986) (xy -1.9431 -0.429768)
			)
			(stroke
				(width 0)
				(type default)
			)
			(fill yes)
			(layer "F.Fab")
		)
		(pad "1" smd rect
			(at -0.94996 -0.649986)
			(size 0.4318 0.6096)
			(layers "F.Cu" "F.Mask" "F.Paste")
			(net "GPU_FPGA_EROT_RECOV_N")
		)
		(pad "2" smd rect
			(at -0.94996 0)
			(size 0.4318 0.6096)
			(layers "F.Cu" "F.Mask" "F.Paste")
			(net "GND")
		)
		(pad "3" smd rect
			(at -0.94996 0.649986)
			(size 0.4318 0.6096)
			(layers "F.Cu" "F.Mask" "F.Paste")
			(net "GND")
		)
		(pad "4" smd rect
			(at 0.94996 0.649986)
			(size 0.4318 0.6096)
			(layers "F.Cu" "F.Mask" "F.Paste")
			(net "NC_U257_2Y")
		)
		(pad "5" smd rect
			(at 0.94996 0)
			(size 0.4318 0.6096)
			(layers "F.Cu" "F.Mask" "F.Paste")
			(net "P3V3_AUX")
		)
		(pad "6" smd rect
			(at 0.94996 -0.649986)
			(size 0.4318 0.6096)
			(layers "F.Cu" "F.Mask" "F.Paste")
			(net "GPU_FPGA_EROT_RECOV_BUF_R_N")
		)
	)
	(footprint ""
		(layer "F.Cu")
		(at 331.224636 -16.401288)
		(property "Reference" "R2452"
			(at 0 0 0)
			(layer "F.SilkS")
			(hide yes)
			(effects
				(font
					(size 1.27 1.27)
				)
			)
		)
		(property "Value" ""
			(at 0 0 0)
			(layer "F.Fab")
			(effects
				(font
					(size 1.27 1.27)
				)
			)
		)
		(duplicate_pad_numbers_are_jumpers no)
		(fp_line
			(start -0.7874 -0.4064)
			(end 0.7874 -0.4064)
			(stroke
				(width 0.1524)
				(type default)
			)
			(layer "F.SilkS")
		)
		(fp_line
			(start -0.7874 0.4064)
			(end -0.7874 -0.4064)
			(stroke
				(width 0.1524)
				(type default)
			)
			(layer "F.SilkS")
		)
		(fp_line
			(start 0.7874 -0.4064)
			(end 0.7874 0.4064)
			(stroke
				(width 0.1524)
				(type default)
			)
			(layer "F.SilkS")
		)
		(fp_line
			(start 0.7874 0.4064)
			(end -0.7874 0.4064)
			(stroke
				(width 0.1524)
				(type default)
			)
			(layer "F.SilkS")
		)
		(fp_line
			(start -0.67945 -0.305054)
			(end -0.12065 -0.305054)
			(stroke
				(width 0.1)
				(type default)
			)
			(layer "F.Fab")
		)
		(fp_line
			(start -0.67945 0.3048)
			(end -0.67945 -0.305054)
			(stroke
				(width 0.1)
				(type default)
			)
			(layer "F.Fab")
		)
		(fp_line
			(start -0.12065 -0.305054)
			(end -0.12065 -0.2794)
			(stroke
				(width 0.1)
				(type default)
			)
			(layer "F.Fab")
		)
		(fp_line
			(start -0.12065 -0.2794)
			(end 0.12065 -0.2794)
			(stroke
				(width 0.1)
				(type default)
			)
			(layer "F.Fab")
		)
		(fp_line
			(start -0.12065 0.2794)
			(end -0.12065 0.3048)
			(stroke
				(width 0.1)
				(type default)
			)
			(layer "F.Fab")
		)
		(fp_line
			(start -0.12065 0.3048)
			(end -0.67945 0.3048)
			(stroke
				(width 0.1)
				(type default)
			)
			(layer "F.Fab")
		)
		(fp_line
			(start 0.120396 0.2794)
			(end -0.12065 0.2794)
			(stroke
				(width 0.1)
				(type default)
			)
			(layer "F.Fab")
		)
		(fp_line
			(start 0.120396 0.3048)
			(end 0.120396 0.2794)
			(stroke
				(width 0.1)
				(type default)
			)
			(layer "F.Fab")
		)
		(fp_line
			(start 0.12065 -0.3048)
			(end 0.67945 -0.3048)
			(stroke
				(width 0.1)
				(type default)
			)
			(layer "F.Fab")
		)
		(fp_line
			(start 0.12065 -0.2794)
			(end 0.12065 -0.3048)
			(stroke
				(width 0.1)
				(type default)
			)
			(layer "F.Fab")
		)
		(fp_line
			(start 0.67945 -0.3048)
			(end 0.67945 0.3048)
			(stroke
				(width 0.1)
				(type default)
			)
			(layer "F.Fab")
		)
		(fp_line
			(start 0.67945 0.3048)
			(end 0.120396 0.3048)
			(stroke
				(width 0.1)
				(type default)
			)
			(layer "F.Fab")
		)
		(pad "1" smd circle
			(at -0.40005 0)
			(size 0 0)
			(layers "F.Cu" "F.Mask" "F.Paste")
			(net "FM_ESPI_PLD_R_EN")
		)
		(pad "2" smd circle
			(at 0.40005 0)
			(size 0 0)
			(layers "F.Cu" "F.Mask" "F.Paste")
			(net "FM_ESPI_PLD_R1_EN")
		)
	)
	(footprint ""
		(layer "F.Cu")
		(at 27.79395 -58.960512 180)
		(property "Reference" "R3103"
			(at 0 0 180)
			(layer "F.SilkS")
			(hide yes)
			(effects
				(font
					(size 1.27 1.27)
				)
			)
		)
		(property "Value" ""
			(at 0 0 180)
			(layer "F.Fab")
			(effects
				(font
					(size 1.27 1.27)
				)
			)
		)
		(duplicate_pad_numbers_are_jumpers no)
		(fp_line
			(start 0.7874 0.4064)
			(end -0.7874 0.4064)
			(stroke
				(width 0.1524)
				(type default)
			)
			(layer "F.SilkS")
		)
		(fp_line
			(start 0.7874 -0.4064)
			(end 0.7874 0.4064)
			(stroke
				(width 0.1524)
				(type default)
			)
			(layer "F.SilkS")
		)
		(fp_line
			(start -0.7874 0.4064)
			(end -0.7874 -0.4064)
			(stroke
				(width 0.1524)
				(type default)
			)
			(layer "F.SilkS")
		)
		(fp_line
			(start -0.7874 -0.4064)
			(end 0.7874 -0.4064)
			(stroke
				(width 0.1524)
				(type default)
			)
			(layer "F.SilkS")
		)
		(fp_line
			(start 0.67945 0.3048)
			(end 0.120396 0.3048)
			(stroke
				(width 0.1)
				(type default)
			)
			(layer "F.Fab")
		)
		(fp_line
			(start 0.67945 -0.3048)
			(end 0.67945 0.3048)
			(stroke
				(width 0.1)
				(type default)
			)
			(layer "F.Fab")
		)
		(fp_line
			(start 0.12065 -0.2794)
			(end 0.12065 -0.3048)
			(stroke
				(width 0.1)
				(type default)
			)
			(layer "F.Fab")
		)
		(fp_line
			(start 0.12065 -0.3048)
			(end 0.67945 -0.3048)
			(stroke
				(width 0.1)
				(type default)
			)
			(layer "F.Fab")
		)
		(fp_line
			(start 0.120396 0.3048)
			(end 0.120396 0.2794)
			(stroke
				(width 0.1)
				(type default)
			)
			(layer "F.Fab")
		)
		(fp_line
			(start 0.120396 0.2794)
			(end -0.12065 0.2794)
			(stroke
				(width 0.1)
				(type default)
			)
			(layer "F.Fab")
		)
		(fp_line
			(start -0.12065 0.3048)
			(end -0.67945 0.3048)
			(stroke
				(width 0.1)
				(type default)
			)
			(layer "F.Fab")
		)
		(fp_line
			(start -0.12065 0.2794)
			(end -0.12065 0.3048)
			(stroke
				(width 0.1)
				(type default)
			)
			(layer "F.Fab")
		)
		(fp_line
			(start -0.12065 -0.2794)
			(end 0.12065 -0.2794)
			(stroke
				(width 0.1)
				(type default)
			)
			(layer "F.Fab")
		)
		(fp_line
			(start -0.12065 -0.305054)
			(end -0.12065 -0.2794)
			(stroke
				(width 0.1)
				(type default)
			)
			(layer "F.Fab")
		)
		(fp_line
			(start -0.67945 0.3048)
			(end -0.67945 -0.305054)
			(stroke
				(width 0.1)
				(type default)
			)
			(layer "F.Fab")
		)
		(fp_line
			(start -0.67945 -0.305054)
			(end -0.12065 -0.305054)
			(stroke
				(width 0.1)
				(type default)
			)
			(layer "F.Fab")
		)
		(pad "1" smd circle
			(at -0.40005 0 180)
			(size 0 0)
			(layers "F.Cu" "F.Mask" "F.Paste")
			(net "IRQ_SML0_ALERT_R_N")
		)
		(pad "2" smd circle
			(at 0.40005 0 180)
			(size 0 0)
			(layers "F.Cu" "F.Mask" "F.Paste")
			(net "IRQ_SML0_ALERT_R1_N")
		)
	)
	(footprint ""
		(layer "F.Cu")
		(at 73.506076 -174.903638 180)
		(property "Reference" "PR567"
			(at 0 0 180)
			(layer "F.SilkS")
			(hide yes)
			(effects
				(font
					(size 1.27 1.27)
				)
			)
		)
		(property "Value" ""
			(at 0 0 180)
			(layer "F.Fab")
			(effects
				(font
					(size 1.27 1.27)
				)
			)
		)
		(duplicate_pad_numbers_are_jumpers no)
		(fp_line
			(start 0.7874 0.4064)
			(end -0.7874 0.4064)
			(stroke
				(width 0.1524)
				(type default)
			)
			(layer "F.SilkS")
		)
		(fp_line
			(start 0.7874 -0.4064)
			(end 0.7874 0.4064)
			(stroke
				(width 0.1524)
				(type default)
			)
			(layer "F.SilkS")
		)
		(fp_line
			(start -0.7874 0.4064)
			(end -0.7874 -0.4064)
			(stroke
				(width 0.1524)
				(type default)
			)
			(layer "F.SilkS")
		)
		(fp_line
			(start -0.7874 -0.4064)
			(end 0.7874 -0.4064)
			(stroke
				(width 0.1524)
				(type default)
			)
			(layer "F.SilkS")
		)
		(fp_line
			(start 0.67945 0.3048)
			(end 0.120396 0.3048)
			(stroke
				(width 0.1)
				(type default)
			)
			(layer "F.Fab")
		)
		(fp_line
			(start 0.67945 -0.3048)
			(end 0.67945 0.3048)
			(stroke
				(width 0.1)
				(type default)
			)
			(layer "F.Fab")
		)
		(fp_line
			(start 0.12065 -0.2794)
			(end 0.12065 -0.3048)
			(stroke
				(width 0.1)
				(type default)
			)
			(layer "F.Fab")
		)
		(fp_line
			(start 0.12065 -0.3048)
			(end 0.67945 -0.3048)
			(stroke
				(width 0.1)
				(type default)
			)
			(layer "F.Fab")
		)
		(fp_line
			(start 0.120396 0.3048)
			(end 0.120396 0.2794)
			(stroke
				(width 0.1)
				(type default)
			)
			(layer "F.Fab")
		)
		(fp_line
			(start 0.120396 0.2794)
			(end -0.12065 0.2794)
			(stroke
				(width 0.1)
				(type default)
			)
			(layer "F.Fab")
		)
		(fp_line
			(start -0.12065 0.3048)
			(end -0.67945 0.3048)
			(stroke
				(width 0.1)
				(type default)
			)
			(layer "F.Fab")
		)
		(fp_line
			(start -0.12065 0.2794)
			(end -0.12065 0.3048)
			(stroke
				(width 0.1)
				(type default)
			)
			(layer "F.Fab")
		)
		(fp_line
			(start -0.12065 -0.2794)
			(end 0.12065 -0.2794)
			(stroke
				(width 0.1)
				(type default)
			)
			(layer "F.Fab")
		)
		(fp_line
			(start -0.12065 -0.305054)
			(end -0.12065 -0.2794)
			(stroke
				(width 0.1)
				(type default)
			)
			(layer "F.Fab")
		)
		(fp_line
			(start -0.67945 0.3048)
			(end -0.67945 -0.305054)
			(stroke
				(width 0.1)
				(type default)
			)
			(layer "F.Fab")
		)
		(fp_line
			(start -0.67945 -0.305054)
			(end -0.12065 -0.305054)
			(stroke
				(width 0.1)
				(type default)
			)
			(layer "F.Fab")
		)
		(pad "1" smd circle
			(at -0.40005 0 180)
			(size 0 0)
			(layers "F.Cu" "F.Mask" "F.Paste")
			(net "VSENSE_PVCCFA_EHV_CPU1_DN")
		)
		(pad "2" smd circle
			(at 0.40005 0 180)
			(size 0 0)
			(layers "F.Cu" "F.Mask" "F.Paste")
			(net "GND")
		)
	)
	(footprint ""
		(layer "F.Cu")
		(at 126.065026 -336.935572 -90)
		(property "Reference" "PC504_P1_5"
			(at 0 0 270)
			(layer "F.SilkS")
			(hide yes)
			(effects
				(font
					(size 1.27 1.27)
				)
			)
		)
		(property "Value" ""
			(at 0 0 270)
			(layer "F.Fab")
			(effects
				(font
					(size 1.27 1.27)
				)
			)
		)
		(duplicate_pad_numbers_are_jumpers no)
		(fp_line
			(start -0.7874 0.4064)
			(end -0.7874 -0.4064)
			(stroke
				(width 0.1524)
				(type default)
			)
			(layer "F.SilkS")
		)
		(fp_line
			(start 0.7874 0.4064)
			(end -0.7874 0.4064)
			(stroke
				(width 0.1524)
				(type default)
			)
			(layer "F.SilkS")
		)
		(fp_line
			(start -0.7874 -0.4064)
			(end 0.7874 -0.4064)
			(stroke
				(width 0.1524)
				(type default)
			)
			(layer "F.SilkS")
		)
		(fp_line
			(start 0.7874 -0.4064)
			(end 0.7874 0.4064)
			(stroke
				(width 0.1524)
				(type default)
			)
			(layer "F.SilkS")
		)
		(fp_line
			(start -0.67945 0.3048)
			(end -0.67945 -0.305054)
			(stroke
				(width 0.1)
				(type default)
			)
			(layer "F.Fab")
		)
		(fp_line
			(start -0.12065 0.3048)
			(end -0.67945 0.3048)
			(stroke
				(width 0.1)
				(type default)
			)
			(layer "F.Fab")
		)
		(fp_line
			(start 0.120396 0.3048)
			(end 0.120396 0.2794)
			(stroke
				(width 0.1)
				(type default)
			)
			(layer "F.Fab")
		)
		(fp_line
			(start 0.67945 0.3048)
			(end 0.120396 0.3048)
			(stroke
				(width 0.1)
				(type default)
			)
			(layer "F.Fab")
		)
		(fp_line
			(start -0.12065 0.2794)
			(end -0.12065 0.3048)
			(stroke
				(width 0.1)
				(type default)
			)
			(layer "F.Fab")
		)
		(fp_line
			(start 0.120396 0.2794)
			(end -0.12065 0.2794)
			(stroke
				(width 0.1)
				(type default)
			)
			(layer "F.Fab")
		)
		(fp_line
			(start -0.12065 -0.2794)
			(end 0.12065 -0.2794)
			(stroke
				(width 0.1)
				(type default)
			)
			(layer "F.Fab")
		)
		(fp_line
			(start 0.12065 -0.2794)
			(end 0.12065 -0.3048)
			(stroke
				(width 0.1)
				(type default)
			)
			(layer "F.Fab")
		)
		(fp_line
			(start 0.12065 -0.3048)
			(end 0.67945 -0.3048)
			(stroke
				(width 0.1)
				(type default)
			)
			(layer "F.Fab")
		)
		(fp_line
			(start 0.67945 -0.3048)
			(end 0.67945 0.3048)
			(stroke
				(width 0.1)
				(type default)
			)
			(layer "F.Fab")
		)
		(fp_line
			(start -0.67945 -0.305054)
			(end -0.12065 -0.305054)
			(stroke
				(width 0.1)
				(type default)
			)
			(layer "F.Fab")
		)
		(fp_line
			(start -0.12065 -0.305054)
			(end -0.12065 -0.2794)
			(stroke
				(width 0.1)
				(type default)
			)
			(layer "F.Fab")
		)
		(pad "1" smd circle
			(at -0.40005 0 270)
			(size 0 0)
			(layers "F.Cu" "F.Mask" "F.Paste")
			(net "PVCCIN_CPU1_PVCC")
		)
		(pad "2" smd circle
			(at 0.40005 0 270)
			(size 0 0)
			(layers "F.Cu" "F.Mask" "F.Paste")
			(net "GND")
		)
	)
	(footprint ""
		(layer "F.Cu")
		(at 371.791738 -413.90443 -90)
		(property "Reference" "R4207"
			(at 0 0 270)
			(layer "F.SilkS")
			(hide yes)
			(effects
				(font
					(size 1.27 1.27)
				)
			)
		)
		(property "Value" ""
			(at 0 0 270)
			(layer "F.Fab")
			(effects
				(font
					(size 1.27 1.27)
				)
			)
		)
		(duplicate_pad_numbers_are_jumpers no)
		(fp_line
			(start -0.7874 0.4064)
			(end -0.7874 -0.4064)
			(stroke
				(width 0.1524)
				(type default)
			)
			(layer "F.SilkS")
		)
		(fp_line
			(start 0.7874 0.4064)
			(end -0.7874 0.4064)
			(stroke
				(width 0.1524)
				(type default)
			)
			(layer "F.SilkS")
		)
		(fp_line
			(start -0.7874 -0.4064)
			(end 0.7874 -0.4064)
			(stroke
				(width 0.1524)
				(type default)
			)
			(layer "F.SilkS")
		)
		(fp_line
			(start 0.7874 -0.4064)
			(end 0.7874 0.4064)
			(stroke
				(width 0.1524)
				(type default)
			)
			(layer "F.SilkS")
		)
		(fp_line
			(start -0.67945 0.3048)
			(end -0.67945 -0.305054)
			(stroke
				(width 0.1)
				(type default)
			)
			(layer "F.Fab")
		)
		(fp_line
			(start -0.12065 0.3048)
			(end -0.67945 0.3048)
			(stroke
				(width 0.1)
				(type default)
			)
			(layer "F.Fab")
		)
		(fp_line
			(start 0.120396 0.3048)
			(end 0.120396 0.2794)
			(stroke
				(width 0.1)
				(type default)
			)
			(layer "F.Fab")
		)
		(fp_line
			(start 0.67945 0.3048)
			(end 0.120396 0.3048)
			(stroke
				(width 0.1)
				(type default)
			)
			(layer "F.Fab")
		)
		(fp_line
			(start -0.12065 0.2794)
			(end -0.12065 0.3048)
			(stroke
				(width 0.1)
				(type default)
			)
			(layer "F.Fab")
		)
		(fp_line
			(start 0.120396 0.2794)
			(end -0.12065 0.2794)
			(stroke
				(width 0.1)
				(type default)
			)
			(layer "F.Fab")
		)
		(fp_line
			(start -0.12065 -0.2794)
			(end 0.12065 -0.2794)
			(stroke
				(width 0.1)
				(type default)
			)
			(layer "F.Fab")
		)
		(fp_line
			(start 0.12065 -0.2794)
			(end 0.12065 -0.3048)
			(stroke
				(width 0.1)
				(type default)
			)
			(layer "F.Fab")
		)
		(fp_line
			(start 0.12065 -0.3048)
			(end 0.67945 -0.3048)
			(stroke
				(width 0.1)
				(type default)
			)
			(layer "F.Fab")
		)
		(fp_line
			(start 0.67945 -0.3048)
			(end 0.67945 0.3048)
			(stroke
				(width 0.1)
				(type default)
			)
			(layer "F.Fab")
		)
		(fp_line
			(start -0.67945 -0.305054)
			(end -0.12065 -0.305054)
			(stroke
				(width 0.1)
				(type default)
			)
			(layer "F.Fab")
		)
		(fp_line
			(start -0.12065 -0.305054)
			(end -0.12065 -0.2794)
			(stroke
				(width 0.1)
				(type default)
			)
			(layer "F.Fab")
		)
		(pad "1" smd circle
			(at -0.40005 0 270)
			(size 0 0)
			(layers "F.Cu" "F.Mask" "F.Paste")
			(net "U270_0_ADD0")
		)
		(pad "2" smd circle
			(at 0.40005 0 270)
			(size 0 0)
			(layers "F.Cu" "F.Mask" "F.Paste")
			(net "GND")
		)
	)
)
